(kicad_pcb
	(version 20260206)
	(generator "pcbnew")
	(generator_version "10.0")
	(general
		(thickness 1.6)
		(legacy_teardrops no)
	)
	(paper "A4")
	(title_block
		(title "15969-1a.1015WZS0858.brd")
		(comment 1 "Tioga Pass / footprint 93 of 295 (SLOT2), pads 151-166 of 166")
	)
	(layers
		(0 "F.Cu" signal "TOP")
		(4 "In1.Cu" signal "L2GND")
		(6 "In2.Cu" signal "L3")
		(8 "In3.Cu" signal "L4")
		(10 "In4.Cu" signal "L5GND")
		(2 "B.Cu" signal "BOTTOM")
		(9 "F.Adhes" user "F.Adhesive")
		(11 "B.Adhes" user "B.Adhesive")
		(13 "F.Paste" user "Package Geometry/Pastemask Top")
		(15 "B.Paste" user "Package Geometry/Pastemask Bottom")
		(5 "F.SilkS" user "Ref Des/Silkscreen Top")
		(7 "B.SilkS" user "Ref Des/Silkscreen Bottom")
		(1 "F.Mask" user "Board Geometry/Soldermask Top")
		(3 "B.Mask" user "Board Geometry/Soldermask Bottom")
		(17 "Dwgs.User" user "User.Drawings")
		(19 "Cmts.User" user "User.Comments")
		(21 "Eco1.User" user "User.Eco1")
		(23 "Eco2.User" user "User.Eco2")
		(25 "Edge.Cuts" user "Board Geometry/Outline")
		(27 "Margin" user)
		(31 "F.CrtYd" user "Package Geometry/Place Bound Top")
		(29 "B.CrtYd" user "Package Geometry/Place Bound Bottom")
		(35 "F.Fab" user "Ref Des/Assembly Top")
		(33 "B.Fab" user "Ref Des/Assembly Bottom")
	)
	(footprint ""
		(layer "F.Cu")
		(at 42.729912 -10.500106)
		(property "Reference" "SLOT2"
			(at 0 0 0)
			(layer "F.SilkS")
			(hide yes)
			(effects
				(font
					(size 1.27 1.27)
				)
			)
		)
		(property "Value" "PCISLT164-129-GP"
			(at -15.9639 4.8514 0)
			(unlocked yes)
			(layer "F.Fab")
			(hide yes)
			(effects
				(font
					(size 1.016 1.016)
					(thickness 0.1524)
				)
			)
		)
		(property "Device Type" "10018783-10203TLF"
			(at -15.9639 3.3274 0)
			(unlocked yes)
			(layer "F.Fab")
			(hide yes)
			(effects
				(font
					(size 1.016 1.016)
					(thickness 0.1524)
				)
			)
		)
		(duplicate_pad_numbers_are_jumpers no)
		(pad "B67" thru_hole circle
			(at 56.3499 1.24968)
			(size 1.0668 1.0668)
			(drill 0.7112)
			(layers "*.Cu" "*.Mask")
			(remove_unused_layers no)
			(net "P3E_CPU0_PE1_SS_C_TXN<3>")
			(clearance 0.1778)
			(thermal_gap 0.1778)
		)
		(pad "B68" thru_hole circle
			(at 57.34939 3.24993)
			(size 1.0668 1.0668)
			(drill 0.7112)
			(layers "*.Cu" "*.Mask")
			(remove_unused_layers no)
			(net "GND")
			(clearance 0.1778)
			(thermal_gap 0.1778)
		)
		(pad "B69" thru_hole circle
			(at 58.35015 1.24968)
			(size 1.0668 1.0668)
			(drill 0.7112)
			(layers "*.Cu" "*.Mask")
			(remove_unused_layers no)
			(net "GND")
			(clearance 0.1778)
			(thermal_gap 0.1778)
		)
		(pad "B70" thru_hole circle
			(at 59.34964 3.24993)
			(size 1.0668 1.0668)
			(drill 0.7112)
			(layers "*.Cu" "*.Mask")
			(remove_unused_layers no)
			(net "P3E_CPU0_PE1_SS_C_TXP<2>")
			(clearance 0.1778)
			(thermal_gap 0.1778)
		)
		(pad "B71" thru_hole circle
			(at 60.3504 1.24968)
			(size 1.0668 1.0668)
			(drill 0.7112)
			(layers "*.Cu" "*.Mask")
			(remove_unused_layers no)
			(net "P3E_CPU0_PE1_SS_C_TXN<2>")
			(clearance 0.1778)
			(thermal_gap 0.1778)
		)
		(pad "B72" thru_hole circle
			(at 61.34989 3.24993)
			(size 1.0668 1.0668)
			(drill 0.7112)
			(layers "*.Cu" "*.Mask")
			(remove_unused_layers no)
			(net "GND")
			(clearance 0.1778)
			(thermal_gap 0.1778)
		)
		(pad "B73" thru_hole circle
			(at 62.34938 1.24968)
			(size 1.0668 1.0668)
			(drill 0.7112)
			(layers "*.Cu" "*.Mask")
			(remove_unused_layers no)
			(net "GND")
			(clearance 0.1778)
			(thermal_gap 0.1778)
		)
		(pad "B74" thru_hole circle
			(at 63.35014 3.24993)
			(size 1.0668 1.0668)
			(drill 0.7112)
			(layers "*.Cu" "*.Mask")
			(remove_unused_layers no)
			(net "P3E_CPU0_PE1_SS_C_TXP<1>")
			(clearance 0.1778)
			(thermal_gap 0.1778)
		)
		(pad "B75" thru_hole circle
			(at 64.34963 1.24968)
			(size 1.0668 1.0668)
			(drill 0.7112)
			(layers "*.Cu" "*.Mask")
			(remove_unused_layers no)
			(net "P3E_CPU0_PE1_SS_C_TXN<1>")
			(clearance 0.1778)
			(thermal_gap 0.1778)
		)
		(pad "B76" thru_hole circle
			(at 65.35039 3.24993)
			(size 1.0668 1.0668)
			(drill 0.7112)
			(layers "*.Cu" "*.Mask")
			(remove_unused_layers no)
			(net "GND")
			(clearance 0.1778)
			(thermal_gap 0.1778)
		)
		(pad "B77" thru_hole circle
			(at 66.34988 1.24968)
			(size 1.0668 1.0668)
			(drill 0.7112)
			(layers "*.Cu" "*.Mask")
			(remove_unused_layers no)
			(net "GND")
			(clearance 0.1778)
			(thermal_gap 0.1778)
		)
		(pad "B78" thru_hole circle
			(at 67.34937 3.24993)
			(size 1.0668 1.0668)
			(drill 0.7112)
			(layers "*.Cu" "*.Mask")
			(remove_unused_layers no)
			(net "P3E_CPU0_PE1_SS_C_TXP<0>")
			(clearance 0.1778)
			(thermal_gap 0.1778)
		)
		(pad "B79" thru_hole circle
			(at 68.35013 1.24968)
			(size 1.0668 1.0668)
			(drill 0.7112)
			(layers "*.Cu" "*.Mask")
			(remove_unused_layers no)
			(net "P3E_CPU0_PE1_SS_C_TXN<0>")
			(clearance 0.1778)
			(thermal_gap 0.1778)
		)
		(pad "B80" thru_hole circle
			(at 69.34962 3.24993)
			(size 1.0668 1.0668)
			(drill 0.7112)
			(layers "*.Cu" "*.Mask")
			(remove_unused_layers no)
			(net "GND")
			(clearance 0.1778)
			(thermal_gap 0.1778)
		)
		(pad "B81" thru_hole circle
			(at 70.35038 1.24968)
			(size 1.0668 1.0668)
			(drill 0.7112)
			(layers "*.Cu" "*.Mask")
			(remove_unused_layers no)
			(net "PCIE_SLOT2_PRSNT2_4_N")
			(clearance 0.1778)
			(thermal_gap 0.1778)
		)
		(pad "B82" thru_hole circle
			(at 71.34987 3.24993)
			(size 1.0668 1.0668)
			(drill 0.7112)
			(layers "*.Cu" "*.Mask")
			(remove_unused_layers no)
			(net "TP_RSVD_SLOT2_PIN82")
			(clearance 0.1778)
			(thermal_gap 0.1778)
		)
	)
)
